# T6G (Grand Teton) — schematic netlist excerpt (pin names and nets, part order shuffled) for the footprints in the layout excerpt that follows; sources: Cadence DE-HDL packaged netlist, KiCad conversion of 04192023_DAF0TMB3IC0_F0TG_MB_C_brd_V02_OCP.brd

PR268  Q_RES  0 5% CHIP  pkg 0402LF  page 219 : A = PVDDCR_CPU1_P1_VOS4 ; B = PVDDCR_CPU1_P1
R537  Q_RES  2.2K 5% CHIP  pkg 0402LF  page 54 : A = CPU1_XTRIG_L4 ; B = PVDD18_S5_P1
PC6018  Q_CAP  22UF 4V 20% X6S  pkg C0805  page 270 : A = P1V2_AUX ; B = GND

(kicad_pcb
	(version 20260206)
	(generator "pcbnew")
	(generator_version "10.0")
	(general
		(thickness 1.6)
		(legacy_teardrops no)
	)
	(paper "A4")
	(title_block
		(title "04192023_DAF0TMB3IC0_F0TG_MB_C_brd_V02_OCP.brd")
		(comment 1 "Grand Teton / footprints 6277-6279 of 8354")
	)
	(layers
		(0 "F.Cu" signal "TOP")
		(4 "In1.Cu" signal "GND")
		(6 "In2.Cu" signal "IN1")
		(8 "In3.Cu" signal "GND1")
		(10 "In4.Cu" signal "IN2")
		(12 "In5.Cu" signal "GND2")
		(14 "In6.Cu" signal "IN3")
		(16 "In7.Cu" signal "GND3")
		(18 "In8.Cu" signal "VCC")
		(20 "In9.Cu" signal "VCC1")
		(22 "In10.Cu" signal "GND4")
		(24 "In11.Cu" signal "IN4")
		(26 "In12.Cu" signal "GND5")
		(28 "In13.Cu" signal "IN5")
		(30 "In14.Cu" signal "GND6")
		(32 "In15.Cu" signal "IN6")
		(34 "In16.Cu" signal "GND7")
		(2 "B.Cu" signal "BOTTOM")
		(9 "F.Adhes" user "F.Adhesive")
		(11 "B.Adhes" user "B.Adhesive")
		(13 "F.Paste" user "Package Geometry/Pastemask Top")
		(15 "B.Paste" user "Package Geometry/Pastemask Bottom")
		(5 "F.SilkS" user "Ref Des/Silkscreen Top")
		(7 "B.SilkS" user "Ref Des/Silkscreen Bottom")
		(1 "F.Mask" user "Board Geometry/Soldermask Top")
		(3 "B.Mask" user "Board Geometry/Soldermask Bottom")
		(17 "Dwgs.User" user "User.Drawings")
		(19 "Cmts.User" user "User.Comments")
		(21 "Eco1.User" user "User.Eco1")
		(23 "Eco2.User" user "User.Eco2")
		(25 "Edge.Cuts" user "Board Geometry/Outline")
		(27 "Margin" user)
		(31 "F.CrtYd" user "Package Geometry/Place Bound Top")
		(29 "B.CrtYd" user "Package Geometry/Place Bound Bottom")
		(35 "F.Fab" user "Ref Des/Assembly Top")
		(33 "B.Fab" user "Ref Des/Assembly Bottom")
	)
	(footprint ""
		(layer "B.Cu")
		(at 130.104642 -74.43724)
		(property "Reference" "PC6018"
			(at 0 0 0)
			(layer "B.SilkS")
			(hide yes)
			(effects
				(font
					(size 1.27 1.27)
				)
				(justify mirror)
			)
		)
		(property "Value" ""
			(at 0 0 0)
			(layer "B.Fab")
			(effects
				(font
					(size 1.27 1.27)
				)
				(justify mirror)
			)
		)
		(duplicate_pad_numbers_are_jumpers no)
		(fp_line
			(start -1.524 -0.762)
			(end -1.524 0.762)
			(stroke
				(width 0.1524)
				(type default)
			)
			(layer "B.SilkS")
		)
		(fp_line
			(start -1.524 0.762)
			(end 1.524 0.762)
			(stroke
				(width 0.1524)
				(type default)
			)
			(layer "B.SilkS")
		)
		(fp_line
			(start 1.524 -0.762)
			(end -1.524 -0.762)
			(stroke
				(width 0.1524)
				(type default)
			)
			(layer "B.SilkS")
		)
		(fp_line
			(start 1.524 0.762)
			(end 1.524 -0.762)
			(stroke
				(width 0.1524)
				(type default)
			)
			(layer "B.SilkS")
		)
		(fp_line
			(start -1.1049 -0.724916)
			(end 1.1049 -0.724916)
			(stroke
				(width 0.1)
				(type default)
			)
			(layer "B.Fab")
		)
		(fp_line
			(start -1.1049 0.724916)
			(end -1.1049 -0.724916)
			(stroke
				(width 0.1)
				(type default)
			)
			(layer "B.Fab")
		)
		(fp_line
			(start 1.1049 -0.724916)
			(end 1.1049 0.724916)
			(stroke
				(width 0.1)
				(type default)
			)
			(layer "B.Fab")
		)
		(fp_line
			(start 1.1049 0.724916)
			(end -1.1049 0.724916)
			(stroke
				(width 0.1)
				(type default)
			)
			(layer "B.Fab")
		)
		(pad "1" smd rect
			(at 0.889 0)
			(size 1.016 1.27)
			(layers "B.Cu" "B.Mask" "B.Paste")
			(net "P1V2_AUX")
		)
		(pad "2" smd rect
			(at -0.889 0)
			(size 1.016 1.27)
			(layers "B.Cu" "B.Mask" "B.Paste")
			(net "GND")
		)
	)
	(footprint ""
		(layer "B.Cu")
		(at 92.281502 -205.14945 90)
		(property "Reference" "R537"
			(at 0 0 90)
			(layer "B.SilkS")
			(hide yes)
			(effects
				(font
					(size 1.27 1.27)
				)
				(justify mirror)
			)
		)
		(property "Value" ""
			(at 0 0 90)
			(layer "B.Fab")
			(effects
				(font
					(size 1.27 1.27)
				)
				(justify mirror)
			)
		)
		(duplicate_pad_numbers_are_jumpers no)
		(fp_line
			(start 0.7874 -0.4064)
			(end -0.7874 -0.4064)
			(stroke
				(width 0.1524)
				(type default)
			)
			(layer "B.SilkS")
		)
		(fp_line
			(start -0.7874 -0.4064)
			(end -0.7874 0.4064)
			(stroke
				(width 0.1524)
				(type default)
			)
			(layer "B.SilkS")
		)
		(fp_line
			(start 0.7874 0.4064)
			(end 0.7874 -0.4064)
			(stroke
				(width 0.1524)
				(type default)
			)
			(layer "B.SilkS")
		)
		(fp_line
			(start -0.7874 0.4064)
			(end 0.7874 0.4064)
			(stroke
				(width 0.1524)
				(type default)
			)
			(layer "B.SilkS")
		)
		(fp_line
			(start 0.67945 -0.305054)
			(end 0.12065 -0.305054)
			(stroke
				(width 0.1)
				(type default)
			)
			(layer "B.Fab")
		)
		(fp_line
			(start 0.12065 -0.305054)
			(end 0.12065 -0.2794)
			(stroke
				(width 0.1)
				(type default)
			)
			(layer "B.Fab")
		)
		(fp_line
			(start -0.12065 -0.3048)
			(end -0.67945 -0.3048)
			(stroke
				(width 0.1)
				(type default)
			)
			(layer "B.Fab")
		)
		(fp_line
			(start -0.67945 -0.3048)
			(end -0.67945 0.3048)
			(stroke
				(width 0.1)
				(type default)
			)
			(layer "B.Fab")
		)
		(fp_line
			(start 0.12065 -0.2794)
			(end -0.12065 -0.2794)
			(stroke
				(width 0.1)
				(type default)
			)
			(layer "B.Fab")
		)
		(fp_line
			(start -0.12065 -0.2794)
			(end -0.12065 -0.3048)
			(stroke
				(width 0.1)
				(type default)
			)
			(layer "B.Fab")
		)
		(fp_line
			(start 0.12065 0.2794)
			(end 0.12065 0.3048)
			(stroke
				(width 0.1)
				(type default)
			)
			(layer "B.Fab")
		)
		(fp_line
			(start -0.120396 0.2794)
			(end 0.12065 0.2794)
			(stroke
				(width 0.1)
				(type default)
			)
			(layer "B.Fab")
		)
		(fp_line
			(start 0.67945 0.3048)
			(end 0.67945 -0.305054)
			(stroke
				(width 0.1)
				(type default)
			)
			(layer "B.Fab")
		)
		(fp_line
			(start 0.12065 0.3048)
			(end 0.67945 0.3048)
			(stroke
				(width 0.1)
				(type default)
			)
			(layer "B.Fab")
		)
		(fp_line
			(start -0.120396 0.3048)
			(end -0.120396 0.2794)
			(stroke
				(width 0.1)
				(type default)
			)
			(layer "B.Fab")
		)
		(fp_line
			(start -0.67945 0.3048)
			(end -0.120396 0.3048)
			(stroke
				(width 0.1)
				(type default)
			)
			(layer "B.Fab")
		)
		(pad "1" smd circle
			(at 0.40005 0 270)
			(size 0 0)
			(layers "B.Cu" "B.Mask" "B.Paste")
			(net "CPU1_XTRIG_L4")
		)
		(pad "2" smd circle
			(at -0.40005 0 270)
			(size 0 0)
			(layers "B.Cu" "B.Mask" "B.Paste")
			(net "PVDD18_S5_P1")
		)
	)
	(footprint ""
		(layer "B.Cu")
		(at 58.213244 -349.386398 -90)
		(property "Reference" "PR268"
			(at 0 0 90)
			(layer "B.SilkS")
			(hide yes)
			(effects
				(font
					(size 1.27 1.27)
				)
				(justify mirror)
			)
		)
		(property "Value" ""
			(at 0 0 90)
			(layer "B.Fab")
			(effects
				(font
					(size 1.27 1.27)
				)
				(justify mirror)
			)
		)
		(duplicate_pad_numbers_are_jumpers no)
		(fp_line
			(start -0.7874 0.4064)
			(end 0.7874 0.4064)
			(stroke
				(width 0.1524)
				(type default)
			)
			(layer "B.SilkS")
		)
		(fp_line
			(start 0.7874 0.4064)
			(end 0.7874 -0.4064)
			(stroke
				(width 0.1524)
				(type default)
			)
			(layer "B.SilkS")
		)
		(fp_line
			(start -0.7874 -0.4064)
			(end -0.7874 0.4064)
			(stroke
				(width 0.1524)
				(type default)
			)
			(layer "B.SilkS")
		)
		(fp_line
			(start 0.7874 -0.4064)
			(end -0.7874 -0.4064)
			(stroke
				(width 0.1524)
				(type default)
			)
			(layer "B.SilkS")
		)
		(fp_line
			(start -0.67945 0.3048)
			(end -0.120396 0.3048)
			(stroke
				(width 0.1)
				(type default)
			)
			(layer "B.Fab")
		)
		(fp_line
			(start -0.120396 0.3048)
			(end -0.120396 0.2794)
			(stroke
				(width 0.1)
				(type default)
			)
			(layer "B.Fab")
		)
		(fp_line
			(start 0.12065 0.3048)
			(end 0.67945 0.3048)
			(stroke
				(width 0.1)
				(type default)
			)
			(layer "B.Fab")
		)
		(fp_line
			(start 0.67945 0.3048)
			(end 0.67945 -0.305054)
			(stroke
				(width 0.1)
				(type default)
			)
			(layer "B.Fab")
		)
		(fp_line
			(start -0.120396 0.2794)
			(end 0.12065 0.2794)
			(stroke
				(width 0.1)
				(type default)
			)
			(layer "B.Fab")
		)
		(fp_line
			(start 0.12065 0.2794)
			(end 0.12065 0.3048)
			(stroke
				(width 0.1)
				(type default)
			)
			(layer "B.Fab")
		)
		(fp_line
			(start -0.12065 -0.2794)
			(end -0.12065 -0.3048)
			(stroke
				(width 0.1)
				(type default)
			)
			(layer "B.Fab")
		)
		(fp_line
			(start 0.12065 -0.2794)
			(end -0.12065 -0.2794)
			(stroke
				(width 0.1)
				(type default)
			)
			(layer "B.Fab")
		)
		(fp_line
			(start -0.67945 -0.3048)
			(end -0.67945 0.3048)
			(stroke
				(width 0.1)
				(type default)
			)
			(layer "B.Fab")
		)
		(fp_line
			(start -0.12065 -0.3048)
			(end -0.67945 -0.3048)
			(stroke
				(width 0.1)
				(type default)
			)
			(layer "B.Fab")
		)
		(fp_line
			(start 0.12065 -0.305054)
			(end 0.12065 -0.2794)
			(stroke
				(width 0.1)
				(type default)
			)
			(layer "B.Fab")
		)
		(fp_line
			(start 0.67945 -0.305054)
			(end 0.12065 -0.305054)
			(stroke
				(width 0.1)
				(type default)
			)
			(layer "B.Fab")
		)
		(pad "1" smd circle
			(at 0.40005 0 90)
			(size 0 0)
			(layers "B.Cu" "B.Mask" "B.Paste")
			(net "PVDDCR_CPU1_P1_VOS4")
		)
		(pad "2" smd circle
			(at -0.40005 0 90)
			(size 0 0)
			(layers "B.Cu" "B.Mask" "B.Paste")
			(net "PVDDCR_CPU1_P1")
		)
	)
)
